(kicad_pcb
	(version 20260206)
	(generator "pcbnew")
	(generator_version "10.0")
	(general
		(thickness 1.6)
		(legacy_teardrops no)
	)
	(paper "A4")
	(title_block
		(title "04192023_DAF0TMB3IC0_F0TG_MB_C_brd_V02_OCP.brd")
		(comment 1 "Grand Teton / footprint 2335 of 8354 (J69), pads 227-291 of 291")
	)
	(layers
		(0 "F.Cu" signal "TOP")
		(4 "In1.Cu" signal "GND")
		(6 "In2.Cu" signal "IN1")
		(8 "In3.Cu" signal "GND1")
		(10 "In4.Cu" signal "IN2")
		(12 "In5.Cu" signal "GND2")
		(14 "In6.Cu" signal "IN3")
		(16 "In7.Cu" signal "GND3")
		(18 "In8.Cu" signal "VCC")
		(20 "In9.Cu" signal "VCC1")
		(22 "In10.Cu" signal "GND4")
		(24 "In11.Cu" signal "IN4")
		(26 "In12.Cu" signal "GND5")
		(28 "In13.Cu" signal "IN5")
		(30 "In14.Cu" signal "GND6")
		(32 "In15.Cu" signal "IN6")
		(34 "In16.Cu" signal "GND7")
		(2 "B.Cu" signal "BOTTOM")
		(9 "F.Adhes" user "F.Adhesive")
		(11 "B.Adhes" user "B.Adhesive")
		(13 "F.Paste" user "Package Geometry/Pastemask Top")
		(15 "B.Paste" user "Package Geometry/Pastemask Bottom")
		(5 "F.SilkS" user "Ref Des/Silkscreen Top")
		(7 "B.SilkS" user "Ref Des/Silkscreen Bottom")
		(1 "F.Mask" user "Board Geometry/Soldermask Top")
		(3 "B.Mask" user "Board Geometry/Soldermask Bottom")
		(17 "Dwgs.User" user "User.Drawings")
		(19 "Cmts.User" user "User.Comments")
		(21 "Eco1.User" user "User.Eco1")
		(23 "Eco2.User" user "User.Eco2")
		(25 "Edge.Cuts" user "Board Geometry/Outline")
		(27 "Margin" user)
		(31 "F.CrtYd" user "Package Geometry/Place Bound Top")
		(29 "B.CrtYd" user "Package Geometry/Place Bound Bottom")
		(35 "F.Fab" user "Ref Des/Assembly Top")
		(33 "B.Fab" user "Ref Des/Assembly Bottom")
	)
	(footprint ""
		(layer "F.Cu")
		(at 421.962072 -255.560068 180)
		(property "Reference" "J69"
			(at 3.448304 81.947512 0)
			(unlocked yes)
			(layer "F.SilkS")
			(effects
				(font
					(size 0.7874 0.5842)
					(thickness 0.1524)
				)
			)
		)
		(property "Value" ""
			(at 0 0 180)
			(layer "F.Fab")
			(effects
				(font
					(size 1.27 1.27)
				)
			)
		)
		(duplicate_pad_numbers_are_jumpers no)
		(pad "227" smd rect
			(at 2.050034 11.474958 90)
			(size 0.519938 1.4986)
			(layers "F.Cu" "F.Mask" "F.Paste")
			(net "M_H_CPU0_SB_PAR")
		)
		(pad "228" smd rect
			(at 2.050034 12.325096 90)
			(size 0.519938 1.4986)
			(layers "F.Cu" "F.Mask" "F.Paste")
			(net "GND")
		)
		(pad "229" smd rect
			(at 2.050034 13.17498 90)
			(size 0.519938 1.4986)
			(layers "F.Cu" "F.Mask" "F.Paste")
			(net "M_H_CPU0_SB_CS_N<1>")
		)
		(pad "230" smd rect
			(at 2.050034 14.025118 90)
			(size 0.519938 1.4986)
			(layers "F.Cu" "F.Mask" "F.Paste")
			(net "GND")
		)
		(pad "231" smd rect
			(at 2.050034 14.875002 90)
			(size 0.519938 1.4986)
			(layers "F.Cu" "F.Mask" "F.Paste")
			(net "Net_2352")
		)
		(pad "232" smd rect
			(at 2.050034 15.724886 90)
			(size 0.519938 1.4986)
			(layers "F.Cu" "F.Mask" "F.Paste")
			(net "Net_2353")
		)
		(pad "233" smd rect
			(at 2.050034 16.575024 90)
			(size 0.519938 1.4986)
			(layers "F.Cu" "F.Mask" "F.Paste")
			(net "GND")
		)
		(pad "234" smd rect
			(at 2.050034 17.424908 90)
			(size 0.519938 1.4986)
			(layers "F.Cu" "F.Mask" "F.Paste")
			(net "M_H_CPU0_SB_CB<6>")
		)
		(pad "235" smd rect
			(at 2.050034 18.275046 90)
			(size 0.519938 1.4986)
			(layers "F.Cu" "F.Mask" "F.Paste")
			(net "GND")
		)
		(pad "236" smd rect
			(at 2.050034 19.12493 90)
			(size 0.519938 1.4986)
			(layers "F.Cu" "F.Mask" "F.Paste")
			(net "M_H_CPU0_SB_CB<7>")
		)
		(pad "237" smd rect
			(at 2.050034 19.975068 90)
			(size 0.519938 1.4986)
			(layers "F.Cu" "F.Mask" "F.Paste")
			(net "GND")
		)
		(pad "238" smd rect
			(at 2.050034 20.824952 90)
			(size 0.519938 1.4986)
			(layers "F.Cu" "F.Mask" "F.Paste")
			(net "M_H_CPU0_SB_DQS_DN<4>")
		)
		(pad "239" smd rect
			(at 2.050034 21.67509 90)
			(size 0.519938 1.4986)
			(layers "F.Cu" "F.Mask" "F.Paste")
			(net "M_H_CPU0_SB_DQS_DP<4>")
		)
		(pad "240" smd rect
			(at 2.050034 22.524974 90)
			(size 0.519938 1.4986)
			(layers "F.Cu" "F.Mask" "F.Paste")
			(net "GND")
		)
		(pad "241" smd rect
			(at 2.050034 23.375112 90)
			(size 0.519938 1.4986)
			(layers "F.Cu" "F.Mask" "F.Paste")
			(net "M_H_CPU0_SB_CB<2>")
		)
		(pad "242" smd rect
			(at 2.050034 24.224996 90)
			(size 0.519938 1.4986)
			(layers "F.Cu" "F.Mask" "F.Paste")
			(net "GND")
		)
		(pad "243" smd rect
			(at 2.050034 25.07488 90)
			(size 0.519938 1.4986)
			(layers "F.Cu" "F.Mask" "F.Paste")
			(net "M_H_CPU0_SB_CB<3>")
		)
		(pad "244" smd rect
			(at 2.050034 25.925018 90)
			(size 0.519938 1.4986)
			(layers "F.Cu" "F.Mask" "F.Paste")
			(net "GND")
		)
		(pad "245" smd rect
			(at 2.050034 26.774902 90)
			(size 0.519938 1.4986)
			(layers "F.Cu" "F.Mask" "F.Paste")
			(net "M_H_CPU0_SB_DQ<2>")
		)
		(pad "246" smd rect
			(at 2.050034 27.62504 90)
			(size 0.519938 1.4986)
			(layers "F.Cu" "F.Mask" "F.Paste")
			(net "GND")
		)
		(pad "247" smd rect
			(at 2.050034 28.474924 90)
			(size 0.519938 1.4986)
			(layers "F.Cu" "F.Mask" "F.Paste")
			(net "M_H_CPU0_SB_DQ<3>")
		)
		(pad "248" smd rect
			(at 2.050034 29.325062 90)
			(size 0.519938 1.4986)
			(layers "F.Cu" "F.Mask" "F.Paste")
			(net "GND")
		)
		(pad "249" smd rect
			(at 2.050034 30.174946 90)
			(size 0.519938 1.4986)
			(layers "F.Cu" "F.Mask" "F.Paste")
			(net "M_H_CPU0_SB_DQS_DN<5>")
		)
		(pad "250" smd rect
			(at 2.050034 31.025084 90)
			(size 0.519938 1.4986)
			(layers "F.Cu" "F.Mask" "F.Paste")
			(net "M_H_CPU0_SB_DQS_DP<5>")
		)
		(pad "251" smd rect
			(at 2.050034 31.874968 90)
			(size 0.519938 1.4986)
			(layers "F.Cu" "F.Mask" "F.Paste")
			(net "GND")
		)
		(pad "252" smd rect
			(at 2.050034 32.725106 90)
			(size 0.519938 1.4986)
			(layers "F.Cu" "F.Mask" "F.Paste")
			(net "M_H_CPU0_SB_DQ<6>")
		)
		(pad "253" smd rect
			(at 2.050034 33.57499 90)
			(size 0.519938 1.4986)
			(layers "F.Cu" "F.Mask" "F.Paste")
			(net "GND")
		)
		(pad "254" smd rect
			(at 2.050034 34.425128 90)
			(size 0.519938 1.4986)
			(layers "F.Cu" "F.Mask" "F.Paste")
			(net "M_H_CPU0_SB_DQ<7>")
		)
		(pad "255" smd rect
			(at 2.050034 35.275012 90)
			(size 0.519938 1.4986)
			(layers "F.Cu" "F.Mask" "F.Paste")
			(net "GND")
		)
		(pad "256" smd rect
			(at 2.050034 36.124896 90)
			(size 0.519938 1.4986)
			(layers "F.Cu" "F.Mask" "F.Paste")
			(net "M_H_CPU0_SB_DQ<10>")
		)
		(pad "257" smd rect
			(at 2.050034 36.975034 90)
			(size 0.519938 1.4986)
			(layers "F.Cu" "F.Mask" "F.Paste")
			(net "GND")
		)
		(pad "258" smd rect
			(at 2.050034 37.824918 90)
			(size 0.519938 1.4986)
			(layers "F.Cu" "F.Mask" "F.Paste")
			(net "M_H_CPU0_SB_DQ<11>")
		)
		(pad "259" smd rect
			(at 2.050034 38.675056 90)
			(size 0.519938 1.4986)
			(layers "F.Cu" "F.Mask" "F.Paste")
			(net "GND")
		)
		(pad "260" smd rect
			(at 2.050034 39.52494 90)
			(size 0.519938 1.4986)
			(layers "F.Cu" "F.Mask" "F.Paste")
			(net "M_H_CPU0_SB_DQS_DN<6>")
		)
		(pad "261" smd rect
			(at 2.050034 40.375078 90)
			(size 0.519938 1.4986)
			(layers "F.Cu" "F.Mask" "F.Paste")
			(net "M_H_CPU0_SB_DQS_DP<6>")
		)
		(pad "262" smd rect
			(at 2.050034 41.224962 90)
			(size 0.519938 1.4986)
			(layers "F.Cu" "F.Mask" "F.Paste")
			(net "GND")
		)
		(pad "263" smd rect
			(at 2.050034 42.0751 90)
			(size 0.519938 1.4986)
			(layers "F.Cu" "F.Mask" "F.Paste")
			(net "M_H_CPU0_SB_DQ<14>")
		)
		(pad "264" smd rect
			(at 2.050034 42.924984 90)
			(size 0.519938 1.4986)
			(layers "F.Cu" "F.Mask" "F.Paste")
			(net "GND")
		)
		(pad "265" smd rect
			(at 2.050034 43.775122 90)
			(size 0.519938 1.4986)
			(layers "F.Cu" "F.Mask" "F.Paste")
			(net "M_H_CPU0_SB_DQ<15>")
		)
		(pad "266" smd rect
			(at 2.050034 44.625006 90)
			(size 0.519938 1.4986)
			(layers "F.Cu" "F.Mask" "F.Paste")
			(net "GND")
		)
		(pad "267" smd rect
			(at 2.050034 45.47489 90)
			(size 0.519938 1.4986)
			(layers "F.Cu" "F.Mask" "F.Paste")
			(net "M_H_CPU0_SB_DQ<18>")
		)
		(pad "268" smd rect
			(at 2.050034 46.325028 90)
			(size 0.519938 1.4986)
			(layers "F.Cu" "F.Mask" "F.Paste")
			(net "GND")
		)
		(pad "269" smd rect
			(at 2.050034 47.174912 90)
			(size 0.519938 1.4986)
			(layers "F.Cu" "F.Mask" "F.Paste")
			(net "M_H_CPU0_SB_DQ<19>")
		)
		(pad "270" smd rect
			(at 2.050034 48.02505 90)
			(size 0.519938 1.4986)
			(layers "F.Cu" "F.Mask" "F.Paste")
			(net "GND")
		)
		(pad "271" smd rect
			(at 2.050034 48.874934 90)
			(size 0.519938 1.4986)
			(layers "F.Cu" "F.Mask" "F.Paste")
			(net "M_H_CPU0_SB_DQS_DN<7>")
		)
		(pad "272" smd rect
			(at 2.050034 49.725072 90)
			(size 0.519938 1.4986)
			(layers "F.Cu" "F.Mask" "F.Paste")
			(net "M_H_CPU0_SB_DQS_DP<7>")
		)
		(pad "273" smd rect
			(at 2.050034 50.574956 90)
			(size 0.519938 1.4986)
			(layers "F.Cu" "F.Mask" "F.Paste")
			(net "GND")
		)
		(pad "274" smd rect
			(at 2.050034 51.425094 90)
			(size 0.519938 1.4986)
			(layers "F.Cu" "F.Mask" "F.Paste")
			(net "M_H_CPU0_SB_DQ<22>")
		)
		(pad "275" smd rect
			(at 2.050034 52.274978 90)
			(size 0.519938 1.4986)
			(layers "F.Cu" "F.Mask" "F.Paste")
			(net "GND")
		)
		(pad "276" smd rect
			(at 2.050034 53.125116 90)
			(size 0.519938 1.4986)
			(layers "F.Cu" "F.Mask" "F.Paste")
			(net "M_H_CPU0_SB_DQ<23>")
		)
		(pad "277" smd rect
			(at 2.050034 53.975 90)
			(size 0.519938 1.4986)
			(layers "F.Cu" "F.Mask" "F.Paste")
			(net "GND")
		)
		(pad "278" smd rect
			(at 2.050034 54.824884 90)
			(size 0.519938 1.4986)
			(layers "F.Cu" "F.Mask" "F.Paste")
			(net "M_H_CPU0_SB_DQ<26>")
		)
		(pad "279" smd rect
			(at 2.050034 55.675022 90)
			(size 0.519938 1.4986)
			(layers "F.Cu" "F.Mask" "F.Paste")
			(net "GND")
		)
		(pad "280" smd rect
			(at 2.050034 56.524906 90)
			(size 0.519938 1.4986)
			(layers "F.Cu" "F.Mask" "F.Paste")
			(net "M_H_CPU0_SB_DQ<27>")
		)
		(pad "281" smd rect
			(at 2.050034 57.375044 90)
			(size 0.519938 1.4986)
			(layers "F.Cu" "F.Mask" "F.Paste")
			(net "GND")
		)
		(pad "282" smd rect
			(at 2.050034 58.224928 90)
			(size 0.519938 1.4986)
			(layers "F.Cu" "F.Mask" "F.Paste")
			(net "M_H_CPU0_SB_DQS_DN<8>")
		)
		(pad "283" smd rect
			(at 2.050034 59.075066 90)
			(size 0.519938 1.4986)
			(layers "F.Cu" "F.Mask" "F.Paste")
			(net "M_H_CPU0_SB_DQS_DP<8>")
		)
		(pad "284" smd rect
			(at 2.050034 59.92495 90)
			(size 0.519938 1.4986)
			(layers "F.Cu" "F.Mask" "F.Paste")
			(net "GND")
		)
		(pad "285" smd rect
			(at 2.050034 60.775088 90)
			(size 0.519938 1.4986)
			(layers "F.Cu" "F.Mask" "F.Paste")
			(net "M_H_CPU0_SB_DQ<30>")
		)
		(pad "286" smd rect
			(at 2.050034 61.624972 90)
			(size 0.519938 1.4986)
			(layers "F.Cu" "F.Mask" "F.Paste")
			(net "GND")
		)
		(pad "287" smd rect
			(at 2.050034 62.47511 90)
			(size 0.519938 1.4986)
			(layers "F.Cu" "F.Mask" "F.Paste")
			(net "M_H_CPU0_SB_DQ<31>")
		)
		(pad "288" smd rect
			(at 2.050034 63.324994 90)
			(size 0.519938 1.4986)
			(layers "F.Cu" "F.Mask" "F.Paste")
			(net "GND")
		)
		(pad "G1" thru_hole oval
			(at 0 -68.97497 90)
			(size 1.7272 3.4798)
			(drill oval 1.2192 2.4638)
			(layers "*.Cu" "*.Mask")
			(remove_unused_layers no)
			(net "GND")
			(clearance 0.127)
			(thermal_gap 0.127)
		)
		(pad "G2" thru_hole oval
			(at 0 3.875024 90)
			(size 1.7272 3.4798)
			(drill oval 1.2192 2.4638)
			(layers "*.Cu" "*.Mask")
			(remove_unused_layers no)
			(net "GND")
			(clearance 0.127)
			(thermal_gap 0.127)
		)
		(pad "G3" thru_hole oval
			(at 0 68.97497 90)
			(size 1.7272 3.4798)
			(drill oval 1.2192 2.4638)
			(layers "*.Cu" "*.Mask")
			(remove_unused_layers no)
			(net "GND")
			(clearance 0.127)
			(thermal_gap 0.127)
		)
	)
)
